(kicad_pcb
	(version 20260206)
	(generator "pcbnew")
	(generator_version "10.0")
	(general
		(thickness 1.6)
		(legacy_teardrops no)
	)
	(paper "A4")
	(title_block
		(title "03242023_DA0F0TMBIJ0_F0T_Motherboard_J_brd_V01_OCP.brd")
		(comment 1 "Grand Teton / footprints 3248-3255 of 6105")
	)
	(layers
		(0 "F.Cu" signal "TOP")
		(4 "In1.Cu" signal "GND")
		(6 "In2.Cu" signal "IN1")
		(8 "In3.Cu" signal "GND1")
		(10 "In4.Cu" signal "IN2")
		(12 "In5.Cu" signal "GND2")
		(14 "In6.Cu" signal "IN3")
		(16 "In7.Cu" signal "GND3")
		(18 "In8.Cu" signal "VCC")
		(20 "In9.Cu" signal "VCC1")
		(22 "In10.Cu" signal "GND4")
		(24 "In11.Cu" signal "IN4")
		(26 "In12.Cu" signal "GND5")
		(28 "In13.Cu" signal "IN5")
		(30 "In14.Cu" signal "GND6")
		(32 "In15.Cu" signal "IN6")
		(34 "In16.Cu" signal "GND7")
		(2 "B.Cu" signal "BOTTOM")
		(9 "F.Adhes" user "F.Adhesive")
		(11 "B.Adhes" user "B.Adhesive")
		(13 "F.Paste" user "Package Geometry/Pastemask Top")
		(15 "B.Paste" user "Package Geometry/Pastemask Bottom")
		(5 "F.SilkS" user "Ref Des/Silkscreen Top")
		(7 "B.SilkS" user "Ref Des/Silkscreen Bottom")
		(1 "F.Mask" user "Board Geometry/Soldermask Top")
		(3 "B.Mask" user "Board Geometry/Soldermask Bottom")
		(17 "Dwgs.User" user "User.Drawings")
		(19 "Cmts.User" user "User.Comments")
		(21 "Eco1.User" user "User.Eco1")
		(23 "Eco2.User" user "User.Eco2")
		(25 "Edge.Cuts" user "Board Geometry/Outline")
		(27 "Margin" user)
		(31 "F.CrtYd" user "Package Geometry/Place Bound Top")
		(29 "B.CrtYd" user "Package Geometry/Place Bound Bottom")
		(35 "F.Fab" user "Ref Des/Assembly Top")
		(33 "B.Fab" user "Ref Des/Assembly Bottom")
	)
	(footprint ""
		(layer "F.Cu")
		(at 447.565272 -19.506438)
		(property "Reference" "PC2087"
			(at 0 0 0)
			(layer "F.SilkS")
			(hide yes)
			(effects
				(font
					(size 1.27 1.27)
				)
			)
		)
		(property "Value" ""
			(at 0 0 0)
			(layer "F.Fab")
			(effects
				(font
					(size 1.27 1.27)
				)
			)
		)
		(duplicate_pad_numbers_are_jumpers no)
		(fp_line
			(start -0.7874 -0.4064)
			(end 0.7874 -0.4064)
			(stroke
				(width 0.1524)
				(type default)
			)
			(layer "F.SilkS")
		)
		(fp_line
			(start -0.7874 0.4064)
			(end -0.7874 -0.4064)
			(stroke
				(width 0.1524)
				(type default)
			)
			(layer "F.SilkS")
		)
		(fp_line
			(start 0.7874 -0.4064)
			(end 0.7874 0.4064)
			(stroke
				(width 0.1524)
				(type default)
			)
			(layer "F.SilkS")
		)
		(fp_line
			(start 0.7874 0.4064)
			(end -0.7874 0.4064)
			(stroke
				(width 0.1524)
				(type default)
			)
			(layer "F.SilkS")
		)
		(fp_line
			(start -0.67945 -0.305054)
			(end -0.12065 -0.305054)
			(stroke
				(width 0.1)
				(type default)
			)
			(layer "F.Fab")
		)
		(fp_line
			(start -0.67945 0.3048)
			(end -0.67945 -0.305054)
			(stroke
				(width 0.1)
				(type default)
			)
			(layer "F.Fab")
		)
		(fp_line
			(start -0.12065 -0.305054)
			(end -0.12065 -0.2794)
			(stroke
				(width 0.1)
				(type default)
			)
			(layer "F.Fab")
		)
		(fp_line
			(start -0.12065 -0.2794)
			(end 0.12065 -0.2794)
			(stroke
				(width 0.1)
				(type default)
			)
			(layer "F.Fab")
		)
		(fp_line
			(start -0.12065 0.2794)
			(end -0.12065 0.3048)
			(stroke
				(width 0.1)
				(type default)
			)
			(layer "F.Fab")
		)
		(fp_line
			(start -0.12065 0.3048)
			(end -0.67945 0.3048)
			(stroke
				(width 0.1)
				(type default)
			)
			(layer "F.Fab")
		)
		(fp_line
			(start 0.120396 0.2794)
			(end -0.12065 0.2794)
			(stroke
				(width 0.1)
				(type default)
			)
			(layer "F.Fab")
		)
		(fp_line
			(start 0.120396 0.3048)
			(end 0.120396 0.2794)
			(stroke
				(width 0.1)
				(type default)
			)
			(layer "F.Fab")
		)
		(fp_line
			(start 0.12065 -0.3048)
			(end 0.67945 -0.3048)
			(stroke
				(width 0.1)
				(type default)
			)
			(layer "F.Fab")
		)
		(fp_line
			(start 0.12065 -0.2794)
			(end 0.12065 -0.3048)
			(stroke
				(width 0.1)
				(type default)
			)
			(layer "F.Fab")
		)
		(fp_line
			(start 0.67945 -0.3048)
			(end 0.67945 0.3048)
			(stroke
				(width 0.1)
				(type default)
			)
			(layer "F.Fab")
		)
		(fp_line
			(start 0.67945 0.3048)
			(end 0.120396 0.3048)
			(stroke
				(width 0.1)
				(type default)
			)
			(layer "F.Fab")
		)
		(pad "1" smd circle
			(at -0.40005 0)
			(size 0 0)
			(layers "F.Cu" "F.Mask" "F.Paste")
			(net "GND")
		)
		(pad "2" smd circle
			(at 0.40005 0)
			(size 0 0)
			(layers "F.Cu" "F.Mask" "F.Paste")
			(net "P12V_OCP_REG_1")
		)
	)
	(footprint ""
		(layer "F.Cu")
		(at 136.3853 -113.384584)
		(property "Reference" "R4756"
			(at 0 0 0)
			(layer "F.SilkS")
			(hide yes)
			(effects
				(font
					(size 1.27 1.27)
				)
			)
		)
		(property "Value" ""
			(at 0 0 0)
			(layer "F.Fab")
			(effects
				(font
					(size 1.27 1.27)
				)
			)
		)
		(duplicate_pad_numbers_are_jumpers no)
		(fp_line
			(start -0.7874 -0.4064)
			(end 0.7874 -0.4064)
			(stroke
				(width 0.1524)
				(type default)
			)
			(layer "F.SilkS")
		)
		(fp_line
			(start -0.7874 0.4064)
			(end -0.7874 -0.4064)
			(stroke
				(width 0.1524)
				(type default)
			)
			(layer "F.SilkS")
		)
		(fp_line
			(start 0.7874 -0.4064)
			(end 0.7874 0.4064)
			(stroke
				(width 0.1524)
				(type default)
			)
			(layer "F.SilkS")
		)
		(fp_line
			(start 0.7874 0.4064)
			(end -0.7874 0.4064)
			(stroke
				(width 0.1524)
				(type default)
			)
			(layer "F.SilkS")
		)
		(fp_line
			(start -0.67945 -0.305054)
			(end -0.12065 -0.305054)
			(stroke
				(width 0.1)
				(type default)
			)
			(layer "F.Fab")
		)
		(fp_line
			(start -0.67945 0.3048)
			(end -0.67945 -0.305054)
			(stroke
				(width 0.1)
				(type default)
			)
			(layer "F.Fab")
		)
		(fp_line
			(start -0.12065 -0.305054)
			(end -0.12065 -0.2794)
			(stroke
				(width 0.1)
				(type default)
			)
			(layer "F.Fab")
		)
		(fp_line
			(start -0.12065 -0.2794)
			(end 0.12065 -0.2794)
			(stroke
				(width 0.1)
				(type default)
			)
			(layer "F.Fab")
		)
		(fp_line
			(start -0.12065 0.2794)
			(end -0.12065 0.3048)
			(stroke
				(width 0.1)
				(type default)
			)
			(layer "F.Fab")
		)
		(fp_line
			(start -0.12065 0.3048)
			(end -0.67945 0.3048)
			(stroke
				(width 0.1)
				(type default)
			)
			(layer "F.Fab")
		)
		(fp_line
			(start 0.120396 0.2794)
			(end -0.12065 0.2794)
			(stroke
				(width 0.1)
				(type default)
			)
			(layer "F.Fab")
		)
		(fp_line
			(start 0.120396 0.3048)
			(end 0.120396 0.2794)
			(stroke
				(width 0.1)
				(type default)
			)
			(layer "F.Fab")
		)
		(fp_line
			(start 0.12065 -0.3048)
			(end 0.67945 -0.3048)
			(stroke
				(width 0.1)
				(type default)
			)
			(layer "F.Fab")
		)
		(fp_line
			(start 0.12065 -0.2794)
			(end 0.12065 -0.3048)
			(stroke
				(width 0.1)
				(type default)
			)
			(layer "F.Fab")
		)
		(fp_line
			(start 0.67945 -0.3048)
			(end 0.67945 0.3048)
			(stroke
				(width 0.1)
				(type default)
			)
			(layer "F.Fab")
		)
		(fp_line
			(start 0.67945 0.3048)
			(end 0.120396 0.3048)
			(stroke
				(width 0.1)
				(type default)
			)
			(layer "F.Fab")
		)
		(pad "1" smd circle
			(at -0.40005 0)
			(size 0 0)
			(layers "F.Cu" "F.Mask" "F.Paste")
			(net "P3V3_AUX")
		)
		(pad "2" smd circle
			(at 0.40005 0)
			(size 0 0)
			(layers "F.Cu" "F.Mask" "F.Paste")
			(net "OCP_V3_2_AUX_PWR_PLD_EN_R")
		)
	)
	(footprint ""
		(layer "F.Cu")
		(at 415.62909 -408.517344 -90)
		(property "Reference" "C898"
			(at 0 0 270)
			(layer "F.SilkS")
			(hide yes)
			(effects
				(font
					(size 1.27 1.27)
				)
			)
		)
		(property "Value" ""
			(at 0 0 270)
			(layer "F.Fab")
			(effects
				(font
					(size 1.27 1.27)
				)
			)
		)
		(duplicate_pad_numbers_are_jumpers no)
		(fp_line
			(start -0.299974 0.150114)
			(end -0.299974 -0.150114)
			(stroke
				(width 0.1)
				(type default)
			)
			(layer "F.Fab")
		)
		(fp_line
			(start 0.299974 0.150114)
			(end -0.299974 0.150114)
			(stroke
				(width 0.1)
				(type default)
			)
			(layer "F.Fab")
		)
		(fp_line
			(start -0.299974 -0.150114)
			(end 0.299974 -0.150114)
			(stroke
				(width 0.1)
				(type default)
			)
			(layer "F.Fab")
		)
		(fp_line
			(start 0.299974 -0.150114)
			(end 0.299974 0.150114)
			(stroke
				(width 0.1)
				(type default)
			)
			(layer "F.Fab")
		)
		(pad "1" smd rect
			(at -0.2667 0 270)
			(size 0.3048 0.381)
			(layers "F.Cu" "F.Mask" "F.Paste")
			(net "P5E_CPU0_PE3_TX_C_DN<1>")
		)
		(pad "2" smd rect
			(at 0.2667 0 270)
			(size 0.3048 0.381)
			(layers "F.Cu" "F.Mask" "F.Paste")
			(net "P5E_CPU0_PE3_TX_DN<1>")
		)
	)
	(footprint ""
		(layer "F.Cu")
		(at 142.42288 -42.446448)
		(property "Reference" "R3294"
			(at 0 0 0)
			(layer "F.SilkS")
			(hide yes)
			(effects
				(font
					(size 1.27 1.27)
				)
			)
		)
		(property "Value" ""
			(at 0 0 0)
			(layer "F.Fab")
			(effects
				(font
					(size 1.27 1.27)
				)
			)
		)
		(duplicate_pad_numbers_are_jumpers no)
		(fp_line
			(start -0.7874 -0.4064)
			(end 0.7874 -0.4064)
			(stroke
				(width 0.1524)
				(type default)
			)
			(layer "F.SilkS")
		)
		(fp_line
			(start -0.7874 0.4064)
			(end -0.7874 -0.4064)
			(stroke
				(width 0.1524)
				(type default)
			)
			(layer "F.SilkS")
		)
		(fp_line
			(start 0.7874 -0.4064)
			(end 0.7874 0.4064)
			(stroke
				(width 0.1524)
				(type default)
			)
			(layer "F.SilkS")
		)
		(fp_line
			(start 0.7874 0.4064)
			(end -0.7874 0.4064)
			(stroke
				(width 0.1524)
				(type default)
			)
			(layer "F.SilkS")
		)
		(fp_line
			(start -0.67945 -0.305054)
			(end -0.12065 -0.305054)
			(stroke
				(width 0.1)
				(type default)
			)
			(layer "F.Fab")
		)
		(fp_line
			(start -0.67945 0.3048)
			(end -0.67945 -0.305054)
			(stroke
				(width 0.1)
				(type default)
			)
			(layer "F.Fab")
		)
		(fp_line
			(start -0.12065 -0.305054)
			(end -0.12065 -0.2794)
			(stroke
				(width 0.1)
				(type default)
			)
			(layer "F.Fab")
		)
		(fp_line
			(start -0.12065 -0.2794)
			(end 0.12065 -0.2794)
			(stroke
				(width 0.1)
				(type default)
			)
			(layer "F.Fab")
		)
		(fp_line
			(start -0.12065 0.2794)
			(end -0.12065 0.3048)
			(stroke
				(width 0.1)
				(type default)
			)
			(layer "F.Fab")
		)
		(fp_line
			(start -0.12065 0.3048)
			(end -0.67945 0.3048)
			(stroke
				(width 0.1)
				(type default)
			)
			(layer "F.Fab")
		)
		(fp_line
			(start 0.120396 0.2794)
			(end -0.12065 0.2794)
			(stroke
				(width 0.1)
				(type default)
			)
			(layer "F.Fab")
		)
		(fp_line
			(start 0.120396 0.3048)
			(end 0.120396 0.2794)
			(stroke
				(width 0.1)
				(type default)
			)
			(layer "F.Fab")
		)
		(fp_line
			(start 0.12065 -0.3048)
			(end 0.67945 -0.3048)
			(stroke
				(width 0.1)
				(type default)
			)
			(layer "F.Fab")
		)
		(fp_line
			(start 0.12065 -0.2794)
			(end 0.12065 -0.3048)
			(stroke
				(width 0.1)
				(type default)
			)
			(layer "F.Fab")
		)
		(fp_line
			(start 0.67945 -0.3048)
			(end 0.67945 0.3048)
			(stroke
				(width 0.1)
				(type default)
			)
			(layer "F.Fab")
		)
		(fp_line
			(start 0.67945 0.3048)
			(end 0.120396 0.3048)
			(stroke
				(width 0.1)
				(type default)
			)
			(layer "F.Fab")
		)
		(pad "1" smd circle
			(at -0.40005 0)
			(size 0 0)
			(layers "F.Cu" "F.Mask" "F.Paste")
			(net "LED_M2_SSD_0_ACT_N")
		)
		(pad "2" smd circle
			(at 0.40005 0)
			(size 0 0)
			(layers "F.Cu" "F.Mask" "F.Paste")
			(net "LED_HDD_ACTIVITY_N")
		)
	)
	(footprint ""
		(layer "F.Cu")
		(at 333.20228 -336.935572 -90)
		(property "Reference" "PC250_P0_6"
			(at 0 0 270)
			(layer "F.SilkS")
			(hide yes)
			(effects
				(font
					(size 1.27 1.27)
				)
			)
		)
		(property "Value" ""
			(at 0 0 270)
			(layer "F.Fab")
			(effects
				(font
					(size 1.27 1.27)
				)
			)
		)
		(duplicate_pad_numbers_are_jumpers no)
		(fp_line
			(start -0.7874 0.4064)
			(end -0.7874 -0.4064)
			(stroke
				(width 0.1524)
				(type default)
			)
			(layer "F.SilkS")
		)
		(fp_line
			(start 0.7874 0.4064)
			(end -0.7874 0.4064)
			(stroke
				(width 0.1524)
				(type default)
			)
			(layer "F.SilkS")
		)
		(fp_line
			(start -0.7874 -0.4064)
			(end 0.7874 -0.4064)
			(stroke
				(width 0.1524)
				(type default)
			)
			(layer "F.SilkS")
		)
		(fp_line
			(start 0.7874 -0.4064)
			(end 0.7874 0.4064)
			(stroke
				(width 0.1524)
				(type default)
			)
			(layer "F.SilkS")
		)
		(fp_line
			(start -0.67945 0.3048)
			(end -0.67945 -0.305054)
			(stroke
				(width 0.1)
				(type default)
			)
			(layer "F.Fab")
		)
		(fp_line
			(start -0.12065 0.3048)
			(end -0.67945 0.3048)
			(stroke
				(width 0.1)
				(type default)
			)
			(layer "F.Fab")
		)
		(fp_line
			(start 0.120396 0.3048)
			(end 0.120396 0.2794)
			(stroke
				(width 0.1)
				(type default)
			)
			(layer "F.Fab")
		)
		(fp_line
			(start 0.67945 0.3048)
			(end 0.120396 0.3048)
			(stroke
				(width 0.1)
				(type default)
			)
			(layer "F.Fab")
		)
		(fp_line
			(start -0.12065 0.2794)
			(end -0.12065 0.3048)
			(stroke
				(width 0.1)
				(type default)
			)
			(layer "F.Fab")
		)
		(fp_line
			(start 0.120396 0.2794)
			(end -0.12065 0.2794)
			(stroke
				(width 0.1)
				(type default)
			)
			(layer "F.Fab")
		)
		(fp_line
			(start -0.12065 -0.2794)
			(end 0.12065 -0.2794)
			(stroke
				(width 0.1)
				(type default)
			)
			(layer "F.Fab")
		)
		(fp_line
			(start 0.12065 -0.2794)
			(end 0.12065 -0.3048)
			(stroke
				(width 0.1)
				(type default)
			)
			(layer "F.Fab")
		)
		(fp_line
			(start 0.12065 -0.3048)
			(end 0.67945 -0.3048)
			(stroke
				(width 0.1)
				(type default)
			)
			(layer "F.Fab")
		)
		(fp_line
			(start 0.67945 -0.3048)
			(end 0.67945 0.3048)
			(stroke
				(width 0.1)
				(type default)
			)
			(layer "F.Fab")
		)
		(fp_line
			(start -0.67945 -0.305054)
			(end -0.12065 -0.305054)
			(stroke
				(width 0.1)
				(type default)
			)
			(layer "F.Fab")
		)
		(fp_line
			(start -0.12065 -0.305054)
			(end -0.12065 -0.2794)
			(stroke
				(width 0.1)
				(type default)
			)
			(layer "F.Fab")
		)
		(pad "1" smd circle
			(at -0.40005 0 270)
			(size 0 0)
			(layers "F.Cu" "F.Mask" "F.Paste")
			(net "PVCCIN_CPU0_PVCC")
		)
		(pad "2" smd circle
			(at 0.40005 0 270)
			(size 0 0)
			(layers "F.Cu" "F.Mask" "F.Paste")
			(net "GND")
		)
	)
	(footprint ""
		(layer "F.Cu")
		(at 133.728714 -408.517344 -90)
		(property "Reference" "C1524"
			(at 0 0 270)
			(layer "F.SilkS")
			(hide yes)
			(effects
				(font
					(size 1.27 1.27)
				)
			)
		)
		(property "Value" ""
			(at 0 0 270)
			(layer "F.Fab")
			(effects
				(font
					(size 1.27 1.27)
				)
			)
		)
		(duplicate_pad_numbers_are_jumpers no)
		(fp_line
			(start -0.299974 0.150114)
			(end -0.299974 -0.150114)
			(stroke
				(width 0.1)
				(type default)
			)
			(layer "F.Fab")
		)
		(fp_line
			(start 0.299974 0.150114)
			(end -0.299974 0.150114)
			(stroke
				(width 0.1)
				(type default)
			)
			(layer "F.Fab")
		)
		(fp_line
			(start -0.299974 -0.150114)
			(end 0.299974 -0.150114)
			(stroke
				(width 0.1)
				(type default)
			)
			(layer "F.Fab")
		)
		(fp_line
			(start 0.299974 -0.150114)
			(end 0.299974 0.150114)
			(stroke
				(width 0.1)
				(type default)
			)
			(layer "F.Fab")
		)
		(pad "1" smd rect
			(at -0.2667 0 270)
			(size 0.3048 0.381)
			(layers "F.Cu" "F.Mask" "F.Paste")
			(net "P5E_CPU1_PE3_TX_C_DN<11>")
		)
		(pad "2" smd rect
			(at 0.2667 0 270)
			(size 0.3048 0.381)
			(layers "F.Cu" "F.Mask" "F.Paste")
			(net "P5E_CPU1_PE3_TX_DN<11>")
		)
	)
	(footprint ""
		(layer "F.Cu")
		(at 368.105182 -343.902284 90)
		(property "Reference" "PC321"
			(at 0 0 90)
			(layer "F.SilkS")
			(hide yes)
			(effects
				(font
					(size 1.27 1.27)
				)
			)
		)
		(property "Value" ""
			(at 0 0 90)
			(layer "F.Fab")
			(effects
				(font
					(size 1.27 1.27)
				)
			)
		)
		(duplicate_pad_numbers_are_jumpers no)
		(fp_line
			(start -3.400044 1.249934)
			(end 3.400044 1.249934)
			(stroke
				(width 0.1524)
				(type default)
			)
			(layer "F.SilkS")
		)
		(fp_circle
			(center 0 1.249934)
			(end 0 4.649978)
			(stroke
				(width 0.1524)
				(type default)
			)
			(fill no)
			(layer "F.SilkS")
		)
		(fp_poly
			(pts
				(arc
					(start -3.400044 1.249934)
					(mid 0 4.649978)
					(end 3.400044 1.249934)
				)
			)
			(stroke
				(width 0)
				(type default)
			)
			(fill yes)
			(layer "F.SilkS")
		)
		(fp_circle
			(center 0 1.249934)
			(end 0 4.649978)
			(stroke
				(width 0.1)
				(type default)
			)
			(fill no)
			(layer "F.Fab")
		)
		(pad "1" thru_hole rect
			(at 0 0 90)
			(size 1.524 1.524)
			(drill 1.016)
			(layers "*.Cu" "*.Mask")
			(remove_unused_layers no)
			(net "SW_P12V_PVCCIN_CPU0_FLT")
			(clearance 0)
			(padstack
				(mode front_inner_back)
				(layer "Inner"
					(shape circle)
					(size 1.524 1.524)
					(clearance 0)
				)
				(layer "B.Cu"
					(shape rect)
					(size 1.524 1.524)
					(clearance 0)
				)
			)
		)
		(pad "2" thru_hole circle
			(at 0 2.500122 90)
			(size 1.524 1.524)
			(drill 1.016)
			(layers "*.Cu" "*.Mask")
			(remove_unused_layers no)
			(net "GND")
			(clearance 0)
		)
	)
	(footprint ""
		(layer "F.Cu")
		(at 303.553368 -367.337848)
		(property "Reference" "PC721_P0_2"
			(at 0 0 0)
			(layer "F.SilkS")
			(hide yes)
			(effects
				(font
					(size 1.27 1.27)
				)
			)
		)
		(property "Value" ""
			(at 0 0 0)
			(layer "F.Fab")
			(effects
				(font
					(size 1.27 1.27)
				)
			)
		)
		(duplicate_pad_numbers_are_jumpers no)
		(fp_line
			(start -1.524 -0.762)
			(end 1.524 -0.762)
			(stroke
				(width 0.1524)
				(type default)
			)
			(layer "F.SilkS")
		)
		(fp_line
			(start -1.524 0.762)
			(end -1.524 -0.762)
			(stroke
				(width 0.1524)
				(type default)
			)
			(layer "F.SilkS")
		)
		(fp_line
			(start 1.524 -0.762)
			(end 1.524 0.762)
			(stroke
				(width 0.1524)
				(type default)
			)
			(layer "F.SilkS")
		)
		(fp_line
			(start 1.524 0.762)
			(end -1.524 0.762)
			(stroke
				(width 0.1524)
				(type default)
			)
			(layer "F.SilkS")
		)
		(fp_line
			(start -1.1049 -0.724916)
			(end -1.1049 0.724916)
			(stroke
				(width 0.1)
				(type default)
			)
			(layer "F.Fab")
		)
		(fp_line
			(start -1.1049 0.724916)
			(end 1.1049 0.724916)
			(stroke
				(width 0.1)
				(type default)
			)
			(layer "F.Fab")
		)
		(fp_line
			(start 1.1049 -0.724916)
			(end -1.1049 -0.724916)
			(stroke
				(width 0.1)
				(type default)
			)
			(layer "F.Fab")
		)
		(fp_line
			(start 1.1049 0.724916)
			(end 1.1049 -0.724916)
			(stroke
				(width 0.1)
				(type default)
			)
			(layer "F.Fab")
		)
		(pad "1" smd rect
			(at -0.889 0 180)
			(size 1.016 1.27)
			(layers "F.Cu" "F.Mask" "F.Paste")
			(net "SW_P12V_PVCCFA_EHV_FIVRA_CPU0_L")
		)
		(pad "2" smd rect
			(at 0.889 0 180)
			(size 1.016 1.27)
			(layers "F.Cu" "F.Mask" "F.Paste")
			(net "GND")
		)
	)
)
